(kicad_pcb
	(version 20260206)
	(generator "pcbnew")
	(generator_version "10.0")
	(general
		(thickness 1.6)
		(legacy_teardrops no)
	)
	(paper "A4")
	(title_block
		(title "panther-plus-userver — 13130-1b_20150205.brd")
		(comment 1 "Honey Badger (Wiwynn) / footprint 894 of 1509 (DIMM1), pads 1-8 of 210")
	)
	(layers
		(0 "F.Cu" signal "TOP")
		(4 "In1.Cu" signal "L2")
		(6 "In2.Cu" signal "L3")
		(8 "In3.Cu" signal "L4")
		(10 "In4.Cu" signal "L5")
		(12 "In5.Cu" signal "L6")
		(14 "In6.Cu" signal "L7")
		(16 "In7.Cu" signal "L8")
		(18 "In8.Cu" signal "L9")
		(20 "In9.Cu" signal "L10")
		(22 "In10.Cu" signal "L11")
		(2 "B.Cu" signal "BOTTOM")
		(9 "F.Adhes" user "F.Adhesive")
		(11 "B.Adhes" user "B.Adhesive")
		(13 "F.Paste" user "Package Geometry/Pastemask Top")
		(15 "B.Paste" user "Package Geometry/Pastemask Bottom")
		(5 "F.SilkS" user "Ref Des/Silkscreen Top")
		(7 "B.SilkS" user "Ref Des/Silkscreen Bottom")
		(1 "F.Mask" user "Board Geometry/Soldermask Top")
		(3 "B.Mask" user "Board Geometry/Soldermask Bottom")
		(17 "Dwgs.User" user "User.Drawings")
		(19 "Cmts.User" user "User.Comments")
		(21 "Eco1.User" user "User.Eco1")
		(23 "Eco2.User" user "User.Eco2")
		(25 "Edge.Cuts" user "Board Geometry/Outline")
		(27 "Margin" user)
		(31 "F.CrtYd" user "Package Geometry/Place Bound Top")
		(29 "B.CrtYd" user "Package Geometry/Place Bound Bottom")
		(35 "F.Fab" user "Ref Des/Assembly Top")
		(33 "B.Fab" user "Ref Des/Assembly Bottom")
	)
	(footprint ""
		(layer "B.Cu")
		(at 158.500064 -66.699892 180)
		(property "Reference" "DIMM1"
			(at 0 0 0)
			(layer "B.SilkS")
			(hide yes)
			(effects
				(font
					(size 1.27 1.27)
				)
				(justify mirror)
			)
		)
		(property "Value" "DDR3-204P-142-COLAY-1-GP-U"
			(at 41.312338 -16.676878 180)
			(unlocked yes)
			(layer "B.Fab")
			(hide yes)
			(effects
				(font
					(size 1.016 1.016)
					(thickness 0.1524)
				)
				(justify mirror)
			)
		)
		(property "Device Type" "AS0A626-J8R6-7H-COLAY-1"
			(at 41.312338 -18.200878 180)
			(unlocked yes)
			(layer "B.Fab")
			(hide yes)
			(effects
				(font
					(size 1.016 1.016)
					(thickness 0.1524)
				)
				(justify mirror)
			)
		)
		(duplicate_pad_numbers_are_jumpers no)
		(pad "" np_thru_hole circle
			(at -33.399984 0)
			(size 0.254 0.254)
			(drill 1.6002)
			(layers "*.Cu" "*.Mask")
			(clearance 1.0287)
			(thermal_gap 1.0287)
		)
		(pad "" np_thru_hole circle
			(at 33.399984 0)
			(size 0.254 0.254)
			(drill 1.1176)
			(layers "*.Cu" "*.Mask")
			(clearance 0.7874)
			(thermal_gap 0.7874)
		)
		(pad "1" smd custom
			(at -31.649924 -4.100068)
			(size 0.1143 0.1143)
			(layers "B.Cu" "B.Mask" "B.Paste")
			(net "DDR3_M_A_VREF_DQ0")
			(options
				(clearance outline)
				(anchor circle)
			)
			(primitives
				(gr_poly
					(pts
						(xy 0 -0.9017) (xy -0.03175 -0.89916) (xy -0.0635 -0.889) (xy -0.09144 -0.87376) (xy -0.11684 -0.85344)
						(xy -0.13716 -0.82804) (xy -0.1524 -0.8001) (xy -0.16256 -0.76835) (xy -0.1651 -0.7366) (xy -0.1651 -0.44958)
						(xy -0.17272 -0.44196) (xy -0.19812 -0.4064) (xy -0.2032 -0.39624) (xy -0.20701 -0.38735) (xy -0.21209 -0.37719)
						(xy -0.2159 -0.36703) (xy -0.21844 -0.35687) (xy -0.22225 -0.34544) (xy -0.22352 -0.33528) (xy -0.22606 -0.32512)
						(xy -0.22733 -0.31369) (xy -0.22733 -0.30353) (xy -0.2286 -0.2921) (xy -0.22733 -0.28067) (xy -0.22733 -0.27051)
						(xy -0.22606 -0.25908) (xy -0.22352 -0.24892) (xy -0.22225 -0.23876) (xy -0.21844 -0.22733) (xy -0.2159 -0.21717)
						(xy -0.21209 -0.20701) (xy -0.20701 -0.19685) (xy -0.2032 -0.18796) (xy -0.19812 -0.1778) (xy -0.17272 -0.14224)
						(xy -0.1651 -0.13462) (xy -0.1651 0.7366) (xy -0.16256 0.76835) (xy -0.1524 0.8001) (xy -0.13716 0.82804)
						(xy -0.11684 0.85344) (xy -0.09144 0.87376) (xy -0.0635 0.889) (xy -0.03175 0.89916) (xy 0 0.9017)
						(xy 0.03175 0.89916) (xy 0.0635 0.889) (xy 0.09144 0.87376) (xy 0.11684 0.85344) (xy 0.13716 0.82804)
						(xy 0.1524 0.8001) (xy 0.16256 0.76835) (xy 0.1651 0.7366) (xy 0.1651 -0.13462) (xy 0.17272 -0.14224)
						(xy 0.19812 -0.1778) (xy 0.2032 -0.18796) (xy 0.20701 -0.19685) (xy 0.21209 -0.20701) (xy 0.2159 -0.21717)
						(xy 0.21844 -0.22733) (xy 0.22225 -0.23876) (xy 0.22352 -0.24892) (xy 0.22606 -0.25908) (xy 0.22733 -0.27051)
						(xy 0.22733 -0.28067) (xy 0.2286 -0.2921) (xy 0.22733 -0.30353) (xy 0.22733 -0.31369) (xy 0.22606 -0.32512)
						(xy 0.22352 -0.33528) (xy 0.22225 -0.34544) (xy 0.21844 -0.35687) (xy 0.2159 -0.36703) (xy 0.21209 -0.37719)
						(xy 0.20701 -0.38735) (xy 0.2032 -0.39624) (xy 0.19812 -0.4064) (xy 0.17272 -0.44196) (xy 0.1651 -0.44958)
						(xy 0.1651 -0.7366) (xy 0.16256 -0.76835) (xy 0.1524 -0.8001) (xy 0.13716 -0.82804) (xy 0.11684 -0.85344)
						(xy 0.09144 -0.87376) (xy 0.0635 -0.889) (xy 0.03175 -0.89916)
					)
					(width 0)
					(fill yes)
				)
			)
		)
		(pad "2" smd custom
			(at -31.34995 4.100068)
			(size 0.1143 0.1143)
			(layers "B.Cu" "B.Mask" "B.Paste")
			(net "GND")
			(options
				(clearance outline)
				(anchor circle)
			)
			(primitives
				(gr_poly
					(pts
						(xy 0 -0.9017) (xy -0.03175 -0.89916) (xy -0.0635 -0.889) (xy -0.09144 -0.87376) (xy -0.11684 -0.85344)
						(xy -0.13716 -0.82804) (xy -0.1524 -0.8001) (xy -0.16256 -0.76835) (xy -0.1651 -0.7366) (xy -0.1651 0.13462)
						(xy -0.17272 0.14224) (xy -0.19812 0.1778) (xy -0.2032 0.18796) (xy -0.20701 0.19685) (xy -0.21209 0.20701)
						(xy -0.2159 0.21717) (xy -0.21844 0.22733) (xy -0.22225 0.23876) (xy -0.22352 0.24892) (xy -0.22606 0.25908)
						(xy -0.22733 0.27051) (xy -0.22733 0.28067) (xy -0.2286 0.2921) (xy -0.22733 0.30353) (xy -0.22733 0.31369)
						(xy -0.22606 0.32512) (xy -0.22352 0.33528) (xy -0.22225 0.34544) (xy -0.21844 0.35687) (xy -0.2159 0.36703)
						(xy -0.21209 0.37719) (xy -0.20701 0.38735) (xy -0.2032 0.39624) (xy -0.19812 0.4064) (xy -0.17272 0.44196)
						(xy -0.1651 0.44958) (xy -0.1651 0.7366) (xy -0.16256 0.76835) (xy -0.1524 0.8001) (xy -0.13716 0.82804)
						(xy -0.11684 0.85344) (xy -0.09144 0.87376) (xy -0.0635 0.889) (xy -0.03175 0.89916) (xy 0 0.9017)
						(xy 0.03175 0.89916) (xy 0.0635 0.889) (xy 0.09144 0.87376) (xy 0.11684 0.85344) (xy 0.13716 0.82804)
						(xy 0.1524 0.8001) (xy 0.16256 0.76835) (xy 0.1651 0.7366) (xy 0.1651 0.44958) (xy 0.17272 0.44196)
						(xy 0.19812 0.4064) (xy 0.2032 0.39624) (xy 0.20701 0.38735) (xy 0.21209 0.37719) (xy 0.2159 0.36703)
						(xy 0.21844 0.35687) (xy 0.22225 0.34544) (xy 0.22352 0.33528) (xy 0.22606 0.32512) (xy 0.22733 0.31369)
						(xy 0.22733 0.30353) (xy 0.2286 0.2921) (xy 0.22733 0.28067) (xy 0.22733 0.27051) (xy 0.22606 0.25908)
						(xy 0.22352 0.24892) (xy 0.22225 0.23876) (xy 0.21844 0.22733) (xy 0.2159 0.21717) (xy 0.21209 0.20701)
						(xy 0.20701 0.19685) (xy 0.2032 0.18796) (xy 0.19812 0.1778) (xy 0.17272 0.14224) (xy 0.1651 0.13462)
						(xy 0.1651 -0.7366) (xy 0.16256 -0.76835) (xy 0.1524 -0.8001) (xy 0.13716 -0.82804) (xy 0.11684 -0.85344)
						(xy 0.09144 -0.87376) (xy 0.0635 -0.889) (xy 0.03175 -0.89916)
					)
					(width 0)
					(fill yes)
				)
			)
		)
		(pad "3" smd custom
			(at -31.049976 -4.100068)
			(size 0.1143 0.1143)
			(layers "B.Cu" "B.Mask" "B.Paste")
			(net "GND")
			(options
				(clearance outline)
				(anchor circle)
			)
			(primitives
				(gr_poly
					(pts
						(xy 0 -0.9017) (xy -0.03175 -0.89916) (xy -0.0635 -0.889) (xy -0.09144 -0.87376) (xy -0.11684 -0.85344)
						(xy -0.13716 -0.82804) (xy -0.1524 -0.8001) (xy -0.16256 -0.76835) (xy -0.1651 -0.7366) (xy -0.1651 -0.19685)
						(xy -0.17272 -0.18923) (xy -0.17907 -0.18034) (xy -0.18669 -0.17145) (xy -0.19177 -0.16256) (xy -0.19812 -0.15367)
						(xy -0.20828 -0.13335) (xy -0.21971 -0.10287) (xy -0.22225 -0.09271) (xy -0.22479 -0.08128) (xy -0.22606 -0.07112)
						(xy -0.2286 -0.05969) (xy -0.2286 -0.01651) (xy -0.22606 -0.00508) (xy -0.22479 0.00508) (xy -0.22225 0.01651)
						(xy -0.21971 0.02667) (xy -0.20828 0.05715) (xy -0.19812 0.07747) (xy -0.19177 0.08636) (xy -0.18669 0.09525)
						(xy -0.17907 0.10414) (xy -0.17272 0.11303) (xy -0.1651 0.12065) (xy -0.1651 0.7366) (xy -0.16256 0.76835)
						(xy -0.1524 0.8001) (xy -0.13716 0.82804) (xy -0.11684 0.85344) (xy -0.09144 0.87376) (xy -0.0635 0.889)
						(xy -0.03175 0.89916) (xy 0 0.9017) (xy 0.03175 0.89916) (xy 0.0635 0.889) (xy 0.09144 0.87376)
						(xy 0.11684 0.85344) (xy 0.13716 0.82804) (xy 0.1524 0.8001) (xy 0.16256 0.76835) (xy 0.1651 0.7366)
						(xy 0.1651 0.11938) (xy 0.17272 0.11176) (xy 0.19812 0.0762) (xy 0.2032 0.06604) (xy 0.20701 0.05715)
						(xy 0.21209 0.04699) (xy 0.2159 0.03683) (xy 0.21844 0.02667) (xy 0.22225 0.01524) (xy 0.22352 0.00508)
						(xy 0.22606 -0.00508) (xy 0.22733 -0.01651) (xy 0.22733 -0.02667) (xy 0.2286 -0.0381) (xy 0.22733 -0.04953)
						(xy 0.22733 -0.05969) (xy 0.22606 -0.07112) (xy 0.22352 -0.08128) (xy 0.22225 -0.09144) (xy 0.21844 -0.10287)
						(xy 0.2159 -0.11303) (xy 0.21209 -0.12319) (xy 0.20701 -0.13335) (xy 0.2032 -0.14224) (xy 0.19812 -0.1524)
						(xy 0.17272 -0.18796) (xy 0.1651 -0.19558) (xy 0.1651 -0.7366) (xy 0.16256 -0.76835) (xy 0.1524 -0.8001)
						(xy 0.13716 -0.82804) (xy 0.11684 -0.85344) (xy 0.09144 -0.87376) (xy 0.0635 -0.889) (xy 0.03175 -0.89916)
					)
					(width 0)
					(fill yes)
				)
			)
		)
		(pad "4" smd custom
			(at -30.750002 4.100068)
			(size 0.1143 0.1143)
			(layers "B.Cu" "B.Mask" "B.Paste")
			(net "M_A_DQ4")
			(options
				(clearance outline)
				(anchor circle)
			)
			(primitives
				(gr_poly
					(pts
						(xy 0 -0.9017) (xy -0.03175 -0.89916) (xy -0.0635 -0.889) (xy -0.09144 -0.87376) (xy -0.11684 -0.85344)
						(xy -0.13716 -0.82804) (xy -0.1524 -0.8001) (xy -0.16256 -0.76835) (xy -0.1651 -0.7366) (xy -0.1651 -0.11938)
						(xy -0.17272 -0.11176) (xy -0.19812 -0.0762) (xy -0.2032 -0.06604) (xy -0.20701 -0.05715) (xy -0.21209 -0.04699)
						(xy -0.2159 -0.03683) (xy -0.21844 -0.02667) (xy -0.22225 -0.01524) (xy -0.22352 -0.00508) (xy -0.22606 0.00508)
						(xy -0.22733 0.01651) (xy -0.22733 0.02667) (xy -0.2286 0.0381) (xy -0.22733 0.04953) (xy -0.22733 0.05969)
						(xy -0.22606 0.07112) (xy -0.22352 0.08128) (xy -0.22225 0.09144) (xy -0.21844 0.10287) (xy -0.2159 0.11303)
						(xy -0.21209 0.12319) (xy -0.20701 0.13335) (xy -0.2032 0.14224) (xy -0.19812 0.1524) (xy -0.17272 0.18796)
						(xy -0.1651 0.19558) (xy -0.1651 0.7366) (xy -0.16256 0.76835) (xy -0.1524 0.8001) (xy -0.13716 0.82804)
						(xy -0.11684 0.85344) (xy -0.09144 0.87376) (xy -0.0635 0.889) (xy -0.03175 0.89916) (xy 0 0.9017)
						(xy 0.03175 0.89916) (xy 0.0635 0.889) (xy 0.09144 0.87376) (xy 0.11684 0.85344) (xy 0.13716 0.82804)
						(xy 0.1524 0.8001) (xy 0.16256 0.76835) (xy 0.1651 0.7366) (xy 0.1651 0.19685) (xy 0.17272 0.18923)
						(xy 0.17907 0.18034) (xy 0.18669 0.17145) (xy 0.19177 0.16256) (xy 0.19812 0.15367) (xy 0.20828 0.13335)
						(xy 0.21971 0.10287) (xy 0.22225 0.09271) (xy 0.22479 0.08128) (xy 0.22606 0.07112) (xy 0.2286 0.05969)
						(xy 0.2286 0.01651) (xy 0.22606 0.00508) (xy 0.22479 -0.00508) (xy 0.22225 -0.01651) (xy 0.21971 -0.02667)
						(xy 0.20828 -0.05715) (xy 0.19812 -0.07747) (xy 0.19177 -0.08636) (xy 0.18669 -0.09525) (xy 0.17907 -0.10414)
						(xy 0.17272 -0.11303) (xy 0.1651 -0.12065) (xy 0.1651 -0.7366) (xy 0.16256 -0.76835) (xy 0.1524 -0.8001)
						(xy 0.13716 -0.82804) (xy 0.11684 -0.85344) (xy 0.09144 -0.87376) (xy 0.0635 -0.889) (xy 0.03175 -0.89916)
					)
					(width 0)
					(fill yes)
				)
			)
		)
		(pad "5" smd custom
			(at -30.450028 -4.100068)
			(size 0.1143 0.1143)
			(layers "B.Cu" "B.Mask" "B.Paste")
			(net "M_A_DQ0")
			(options
				(clearance outline)
				(anchor circle)
			)
			(primitives
				(gr_poly
					(pts
						(xy 0 -0.9017) (xy -0.03175 -0.89916) (xy -0.0635 -0.889) (xy -0.09144 -0.87376) (xy -0.11684 -0.85344)
						(xy -0.13716 -0.82804) (xy -0.1524 -0.8001) (xy -0.16256 -0.76835) (xy -0.1651 -0.7366) (xy -0.1651 -0.44958)
						(xy -0.17272 -0.44196) (xy -0.19812 -0.4064) (xy -0.2032 -0.39624) (xy -0.20701 -0.38735) (xy -0.21209 -0.37719)
						(xy -0.2159 -0.36703) (xy -0.21844 -0.35687) (xy -0.22225 -0.34544) (xy -0.22352 -0.33528) (xy -0.22606 -0.32512)
						(xy -0.22733 -0.31369) (xy -0.22733 -0.30353) (xy -0.2286 -0.2921) (xy -0.22733 -0.28067) (xy -0.22733 -0.27051)
						(xy -0.22606 -0.25908) (xy -0.22352 -0.24892) (xy -0.22225 -0.23876) (xy -0.21844 -0.22733) (xy -0.2159 -0.21717)
						(xy -0.21209 -0.20701) (xy -0.20701 -0.19685) (xy -0.2032 -0.18796) (xy -0.19812 -0.1778) (xy -0.17272 -0.14224)
						(xy -0.1651 -0.13462) (xy -0.1651 0.7366) (xy -0.16256 0.76835) (xy -0.1524 0.8001) (xy -0.13716 0.82804)
						(xy -0.11684 0.85344) (xy -0.09144 0.87376) (xy -0.0635 0.889) (xy -0.03175 0.89916) (xy 0 0.9017)
						(xy 0.03175 0.89916) (xy 0.0635 0.889) (xy 0.09144 0.87376) (xy 0.11684 0.85344) (xy 0.13716 0.82804)
						(xy 0.1524 0.8001) (xy 0.16256 0.76835) (xy 0.1651 0.7366) (xy 0.1651 -0.13462) (xy 0.17272 -0.14224)
						(xy 0.19812 -0.1778) (xy 0.2032 -0.18796) (xy 0.20701 -0.19685) (xy 0.21209 -0.20701) (xy 0.2159 -0.21717)
						(xy 0.21844 -0.22733) (xy 0.22225 -0.23876) (xy 0.22352 -0.24892) (xy 0.22606 -0.25908) (xy 0.22733 -0.27051)
						(xy 0.22733 -0.28067) (xy 0.2286 -0.2921) (xy 0.22733 -0.30353) (xy 0.22733 -0.31369) (xy 0.22606 -0.32512)
						(xy 0.22352 -0.33528) (xy 0.22225 -0.34544) (xy 0.21844 -0.35687) (xy 0.2159 -0.36703) (xy 0.21209 -0.37719)
						(xy 0.20701 -0.38735) (xy 0.2032 -0.39624) (xy 0.19812 -0.4064) (xy 0.17272 -0.44196) (xy 0.1651 -0.44958)
						(xy 0.1651 -0.7366) (xy 0.16256 -0.76835) (xy 0.1524 -0.8001) (xy 0.13716 -0.82804) (xy 0.11684 -0.85344)
						(xy 0.09144 -0.87376) (xy 0.0635 -0.889) (xy 0.03175 -0.89916)
					)
					(width 0)
					(fill yes)
				)
			)
		)
		(pad "6" smd custom
			(at -30.150054 4.100068)
			(size 0.1143 0.1143)
			(layers "B.Cu" "B.Mask" "B.Paste")
			(net "M_A_DQ5")
			(options
				(clearance outline)
				(anchor circle)
			)
			(primitives
				(gr_poly
					(pts
						(xy 0 -0.9017) (xy -0.03175 -0.89916) (xy -0.0635 -0.889) (xy -0.09144 -0.87376) (xy -0.11684 -0.85344)
						(xy -0.13716 -0.82804) (xy -0.1524 -0.8001) (xy -0.16256 -0.76835) (xy -0.1651 -0.7366) (xy -0.1651 0.13462)
						(xy -0.17272 0.14224) (xy -0.19812 0.1778) (xy -0.2032 0.18796) (xy -0.20701 0.19685) (xy -0.21209 0.20701)
						(xy -0.2159 0.21717) (xy -0.21844 0.22733) (xy -0.22225 0.23876) (xy -0.22352 0.24892) (xy -0.22606 0.25908)
						(xy -0.22733 0.27051) (xy -0.22733 0.28067) (xy -0.2286 0.2921) (xy -0.22733 0.30353) (xy -0.22733 0.31369)
						(xy -0.22606 0.32512) (xy -0.22352 0.33528) (xy -0.22225 0.34544) (xy -0.21844 0.35687) (xy -0.2159 0.36703)
						(xy -0.21209 0.37719) (xy -0.20701 0.38735) (xy -0.2032 0.39624) (xy -0.19812 0.4064) (xy -0.17272 0.44196)
						(xy -0.1651 0.44958) (xy -0.1651 0.7366) (xy -0.16256 0.76835) (xy -0.1524 0.8001) (xy -0.13716 0.82804)
						(xy -0.11684 0.85344) (xy -0.09144 0.87376) (xy -0.0635 0.889) (xy -0.03175 0.89916) (xy 0 0.9017)
						(xy 0.03175 0.89916) (xy 0.0635 0.889) (xy 0.09144 0.87376) (xy 0.11684 0.85344) (xy 0.13716 0.82804)
						(xy 0.1524 0.8001) (xy 0.16256 0.76835) (xy 0.1651 0.7366) (xy 0.1651 0.44958) (xy 0.17272 0.44196)
						(xy 0.19812 0.4064) (xy 0.2032 0.39624) (xy 0.20701 0.38735) (xy 0.21209 0.37719) (xy 0.2159 0.36703)
						(xy 0.21844 0.35687) (xy 0.22225 0.34544) (xy 0.22352 0.33528) (xy 0.22606 0.32512) (xy 0.22733 0.31369)
						(xy 0.22733 0.30353) (xy 0.2286 0.2921) (xy 0.22733 0.28067) (xy 0.22733 0.27051) (xy 0.22606 0.25908)
						(xy 0.22352 0.24892) (xy 0.22225 0.23876) (xy 0.21844 0.22733) (xy 0.2159 0.21717) (xy 0.21209 0.20701)
						(xy 0.20701 0.19685) (xy 0.2032 0.18796) (xy 0.19812 0.1778) (xy 0.17272 0.14224) (xy 0.1651 0.13462)
						(xy 0.1651 -0.7366) (xy 0.16256 -0.76835) (xy 0.1524 -0.8001) (xy 0.13716 -0.82804) (xy 0.11684 -0.85344)
						(xy 0.09144 -0.87376) (xy 0.0635 -0.889) (xy 0.03175 -0.89916)
					)
					(width 0)
					(fill yes)
				)
			)
		)
	)
)
